# SCM (Grand Teton) — schematic netlist excerpt (pin names and nets, part order shuffled) for the footprints in the layout excerpt that follows; sources: Cadence DE-HDL packaged netlist, KiCad conversion of 12092022_DA0F0TMDCD0_F0T_Management_Board_D_brd_V3_OCP.brd

R342  Q_RES  120 1% CHIP  pkg 0402LF  page 20 : A = GND ; B = M_BMC_DDR4_MRAS_N
R73  Q_RES  1K 1% EMPTY  pkg 0402LF  page 11 : A = P3V3_AUX ; B = SGPIO_LD_1

(kicad_pcb
	(version 20260206)
	(generator "pcbnew")
	(generator_version "10.0")
	(general
		(thickness 1.6)
		(legacy_teardrops no)
	)
	(paper "A4")
	(title_block
		(title "12092022_DA0F0TMDCD0_F0T_Management_Board_D_brd_V3_OCP.brd")
		(comment 1 "Grand Teton / footprints 1167-1168 of 1440")
	)
	(layers
		(0 "F.Cu" signal "TOP")
		(4 "In1.Cu" signal "GND")
		(6 "In2.Cu" signal "IN1")
		(8 "In3.Cu" signal "GND1")
		(10 "In4.Cu" signal "IN2")
		(12 "In5.Cu" signal "VCC")
		(14 "In6.Cu" signal "VCC1")
		(16 "In7.Cu" signal "IN3")
		(18 "In8.Cu" signal "GND2")
		(20 "In9.Cu" signal "IN4")
		(22 "In10.Cu" signal "GND3")
		(2 "B.Cu" signal "BOTTOM")
		(9 "F.Adhes" user "F.Adhesive")
		(11 "B.Adhes" user "B.Adhesive")
		(13 "F.Paste" user "Package Geometry/Pastemask Top")
		(15 "B.Paste" user "Package Geometry/Pastemask Bottom")
		(5 "F.SilkS" user "Ref Des/Silkscreen Top")
		(7 "B.SilkS" user "Ref Des/Silkscreen Bottom")
		(1 "F.Mask" user "Board Geometry/Soldermask Top")
		(3 "B.Mask" user "Board Geometry/Soldermask Bottom")
		(17 "Dwgs.User" user "User.Drawings")
		(19 "Cmts.User" user "User.Comments")
		(21 "Eco1.User" user "User.Eco1")
		(23 "Eco2.User" user "User.Eco2")
		(25 "Edge.Cuts" user "Board Geometry/Outline")
		(27 "Margin" user)
		(31 "F.CrtYd" user "Package Geometry/Place Bound Top")
		(29 "B.CrtYd" user "Package Geometry/Place Bound Bottom")
		(35 "F.Fab" user "Ref Des/Assembly Top")
		(33 "B.Fab" user "Ref Des/Assembly Bottom")
	)
	(footprint ""
		(layer "B.Cu")
		(at 39.0652 -106.3752 -90)
		(property "Reference" "R73"
			(at 0 0 90)
			(layer "B.SilkS")
			(hide yes)
			(effects
				(font
					(size 1.27 1.27)
				)
				(justify mirror)
			)
		)
		(property "Value" ""
			(at 0 0 90)
			(layer "B.Fab")
			(effects
				(font
					(size 1.27 1.27)
				)
				(justify mirror)
			)
		)
		(duplicate_pad_numbers_are_jumpers no)
		(fp_line
			(start -0.7874 0.4064)
			(end 0.7874 0.4064)
			(stroke
				(width 0.1524)
				(type default)
			)
			(layer "B.SilkS")
		)
		(fp_line
			(start 0.7874 0.4064)
			(end 0.7874 -0.4064)
			(stroke
				(width 0.1524)
				(type default)
			)
			(layer "B.SilkS")
		)
		(fp_line
			(start -0.7874 -0.4064)
			(end -0.7874 0.4064)
			(stroke
				(width 0.1524)
				(type default)
			)
			(layer "B.SilkS")
		)
		(fp_line
			(start 0.7874 -0.4064)
			(end -0.7874 -0.4064)
			(stroke
				(width 0.1524)
				(type default)
			)
			(layer "B.SilkS")
		)
		(fp_line
			(start -0.67945 0.3048)
			(end -0.120396 0.3048)
			(stroke
				(width 0.1)
				(type default)
			)
			(layer "B.Fab")
		)
		(fp_line
			(start -0.120396 0.3048)
			(end -0.120396 0.2794)
			(stroke
				(width 0.1)
				(type default)
			)
			(layer "B.Fab")
		)
		(fp_line
			(start 0.12065 0.3048)
			(end 0.67945 0.3048)
			(stroke
				(width 0.1)
				(type default)
			)
			(layer "B.Fab")
		)
		(fp_line
			(start 0.67945 0.3048)
			(end 0.67945 -0.305054)
			(stroke
				(width 0.1)
				(type default)
			)
			(layer "B.Fab")
		)
		(fp_line
			(start -0.120396 0.2794)
			(end 0.12065 0.2794)
			(stroke
				(width 0.1)
				(type default)
			)
			(layer "B.Fab")
		)
		(fp_line
			(start 0.12065 0.2794)
			(end 0.12065 0.3048)
			(stroke
				(width 0.1)
				(type default)
			)
			(layer "B.Fab")
		)
		(fp_line
			(start -0.12065 -0.2794)
			(end -0.12065 -0.3048)
			(stroke
				(width 0.1)
				(type default)
			)
			(layer "B.Fab")
		)
		(fp_line
			(start 0.12065 -0.2794)
			(end -0.12065 -0.2794)
			(stroke
				(width 0.1)
				(type default)
			)
			(layer "B.Fab")
		)
		(fp_line
			(start -0.67945 -0.3048)
			(end -0.67945 0.3048)
			(stroke
				(width 0.1)
				(type default)
			)
			(layer "B.Fab")
		)
		(fp_line
			(start -0.12065 -0.3048)
			(end -0.67945 -0.3048)
			(stroke
				(width 0.1)
				(type default)
			)
			(layer "B.Fab")
		)
		(fp_line
			(start 0.12065 -0.305054)
			(end 0.12065 -0.2794)
			(stroke
				(width 0.1)
				(type default)
			)
			(layer "B.Fab")
		)
		(fp_line
			(start 0.67945 -0.305054)
			(end 0.12065 -0.305054)
			(stroke
				(width 0.1)
				(type default)
			)
			(layer "B.Fab")
		)
		(pad "1" smd circle
			(at 0.40005 0 90)
			(size 0 0)
			(layers "B.Cu" "B.Mask" "B.Paste")
			(net "P3V3_AUX")
		)
		(pad "2" smd circle
			(at -0.40005 0 90)
			(size 0 0)
			(layers "B.Cu" "B.Mask" "B.Paste")
			(net "SGPIO_LD_1")
		)
	)
	(footprint ""
		(layer "B.Cu")
		(at 83.16722 -48.618394)
		(property "Reference" "R342"
			(at 0 0 0)
			(layer "B.SilkS")
			(hide yes)
			(effects
				(font
					(size 1.27 1.27)
				)
				(justify mirror)
			)
		)
		(property "Value" ""
			(at 0 0 0)
			(layer "B.Fab")
			(effects
				(font
					(size 1.27 1.27)
				)
				(justify mirror)
			)
		)
		(duplicate_pad_numbers_are_jumpers no)
		(fp_line
			(start -0.7874 -0.4064)
			(end -0.7874 0.4064)
			(stroke
				(width 0.1524)
				(type default)
			)
			(layer "B.SilkS")
		)
		(fp_line
			(start -0.7874 0.4064)
			(end 0.7874 0.4064)
			(stroke
				(width 0.1524)
				(type default)
			)
			(layer "B.SilkS")
		)
		(fp_line
			(start 0.7874 -0.4064)
			(end -0.7874 -0.4064)
			(stroke
				(width 0.1524)
				(type default)
			)
			(layer "B.SilkS")
		)
		(fp_line
			(start 0.7874 0.4064)
			(end 0.7874 -0.4064)
			(stroke
				(width 0.1524)
				(type default)
			)
			(layer "B.SilkS")
		)
		(fp_line
			(start -0.67945 -0.3048)
			(end -0.67945 0.3048)
			(stroke
				(width 0.1)
				(type default)
			)
			(layer "B.Fab")
		)
		(fp_line
			(start -0.67945 0.3048)
			(end -0.120396 0.3048)
			(stroke
				(width 0.1)
				(type default)
			)
			(layer "B.Fab")
		)
		(fp_line
			(start -0.12065 -0.3048)
			(end -0.67945 -0.3048)
			(stroke
				(width 0.1)
				(type default)
			)
			(layer "B.Fab")
		)
		(fp_line
			(start -0.12065 -0.2794)
			(end -0.12065 -0.3048)
			(stroke
				(width 0.1)
				(type default)
			)
			(layer "B.Fab")
		)
		(fp_line
			(start -0.120396 0.2794)
			(end 0.12065 0.2794)
			(stroke
				(width 0.1)
				(type default)
			)
			(layer "B.Fab")
		)
		(fp_line
			(start -0.120396 0.3048)
			(end -0.120396 0.2794)
			(stroke
				(width 0.1)
				(type default)
			)
			(layer "B.Fab")
		)
		(fp_line
			(start 0.12065 -0.305054)
			(end 0.12065 -0.2794)
			(stroke
				(width 0.1)
				(type default)
			)
			(layer "B.Fab")
		)
		(fp_line
			(start 0.12065 -0.2794)
			(end -0.12065 -0.2794)
			(stroke
				(width 0.1)
				(type default)
			)
			(layer "B.Fab")
		)
		(fp_line
			(start 0.12065 0.2794)
			(end 0.12065 0.3048)
			(stroke
				(width 0.1)
				(type default)
			)
			(layer "B.Fab")
		)
		(fp_line
			(start 0.12065 0.3048)
			(end 0.67945 0.3048)
			(stroke
				(width 0.1)
				(type default)
			)
			(layer "B.Fab")
		)
		(fp_line
			(start 0.67945 -0.305054)
			(end 0.12065 -0.305054)
			(stroke
				(width 0.1)
				(type default)
			)
			(layer "B.Fab")
		)
		(fp_line
			(start 0.67945 0.3048)
			(end 0.67945 -0.305054)
			(stroke
				(width 0.1)
				(type default)
			)
			(layer "B.Fab")
		)
		(pad "1" smd circle
			(at 0.40005 0 180)
			(size 0 0)
			(layers "B.Cu" "B.Mask" "B.Paste")
			(net "GND")
		)
		(pad "2" smd circle
			(at -0.40005 0 180)
			(size 0 0)
			(layers "B.Cu" "B.Mask" "B.Paste")
			(net "M_BMC_DDR4_MRAS_N")
		)
	)
)
